(kicad_pcb
	(version 20260206)
	(generator "pcbnew")
	(generator_version "10.0")
	(general
		(thickness 1.6)
		(legacy_teardrops no)
	)
	(paper "A4")
	(title_block
		(title "Wiwynn_Tioga_Pass_MB.brd")
		(comment 1 "Tioga Pass / footprints 2092-2095 of 4770")
	)
	(layers
		(0 "F.Cu" signal "TOP")
		(4 "In1.Cu" signal "L2GND")
		(6 "In2.Cu" signal "L3")
		(8 "In3.Cu" signal "L4GND")
		(10 "In4.Cu" signal "L5")
		(12 "In5.Cu" signal "L6GND")
		(14 "In6.Cu" signal "L7VCC")
		(16 "In7.Cu" signal "L8VCC")
		(18 "In8.Cu" signal "L9GND")
		(20 "In9.Cu" signal "L10")
		(22 "In10.Cu" signal "L11GND")
		(24 "In11.Cu" signal "L12")
		(26 "In12.Cu" signal "L13GND")
		(2 "B.Cu" signal "BOTTOM")
		(9 "F.Adhes" user "F.Adhesive")
		(11 "B.Adhes" user "B.Adhesive")
		(13 "F.Paste" user "Package Geometry/Pastemask Top")
		(15 "B.Paste" user "Package Geometry/Pastemask Bottom")
		(5 "F.SilkS" user "Ref Des/Silkscreen Top")
		(7 "B.SilkS" user "Ref Des/Silkscreen Bottom")
		(1 "F.Mask" user "Board Geometry/Soldermask Top")
		(3 "B.Mask" user "Board Geometry/Soldermask Bottom")
		(17 "Dwgs.User" user "User.Drawings")
		(19 "Cmts.User" user "User.Comments")
		(21 "Eco1.User" user "User.Eco1")
		(23 "Eco2.User" user "User.Eco2")
		(25 "Edge.Cuts" user "Board Geometry/Outline")
		(27 "Margin" user)
		(31 "F.CrtYd" user "Package Geometry/Place Bound Top")
		(29 "B.CrtYd" user "Package Geometry/Place Bound Bottom")
		(35 "F.Fab" user "Ref Des/Assembly Top")
		(33 "B.Fab" user "Ref Des/Assembly Bottom")
	)
	(footprint ""
		(layer "F.Cu")
		(at 87.158068 -140.208 -90)
		(property "Reference" "C2A11"
			(at 1.848866 0.752348 270)
			(unlocked yes)
			(layer "F.SilkS")
			(effects
				(font
					(size 1.27 0.9652)
					(thickness 0.1524)
				)
			)
		)
		(property "Value" ""
			(at 0 0 270)
			(layer "F.Fab")
			(effects
				(font
					(size 1.27 1.27)
				)
			)
		)
		(duplicate_pad_numbers_are_jumpers no)
		(fp_rect
			(start -0.500126 1.598422)
			(end 0.500126 -0.201422)
			(stroke
				(width 0)
				(type default)
			)
			(fill no)
			(layer "F.CrtYd")
		)
		(fp_line
			(start -0.500126 1.598422)
			(end -0.500126 -0.201422)
			(stroke
				(width 0.1)
				(type default)
			)
			(layer "F.Fab")
		)
		(fp_line
			(start 0.500126 1.598422)
			(end -0.500126 1.598422)
			(stroke
				(width 0.1)
				(type default)
			)
			(layer "F.Fab")
		)
		(fp_line
			(start -0.500126 -0.201422)
			(end 0.500126 -0.201422)
			(stroke
				(width 0.1)
				(type default)
			)
			(layer "F.Fab")
		)
		(fp_line
			(start 0.500126 -0.201422)
			(end 0.500126 1.598422)
			(stroke
				(width 0.1)
				(type default)
			)
			(layer "F.Fab")
		)
		(pad "1" smd rect
			(at 0 0 180)
			(size 0.889 0.9906)
			(layers "F.Cu" "F.Mask" "F.Paste")
			(net "PVDDQ_KLM")
		)
		(pad "2" smd rect
			(at 0 1.397 180)
			(size 0.889 0.9906)
			(layers "F.Cu" "F.Mask" "F.Paste")
			(net "GND")
		)
		(zone
			(layer "F.Cu")
			(hatch none 0.5)
			(connect_pads
				(clearance 0)
			)
			(min_thickness 0.25)
			(keepout
				(tracks allowed)
				(vias not_allowed)
				(pads allowed)
				(copperpour not_allowed)
				(footprints allowed)
			)
			(placement
				(enabled no)
				(sheetname "")
			)
			(fill
				(thermal_gap 0.5)
				(thermal_bridge_width 0.5)
				(island_removal_mode 0)
			)
			(polygon
				(pts
					(xy 86.205568 -140.7033) (xy 86.205568 -139.7127) (xy 86.713568 -139.7127) (xy 86.713568 -140.7033)
				)
			)
		)
		(zone
			(layer "F.Cu")
			(hatch none 0.5)
			(connect_pads
				(clearance 0)
			)
			(min_thickness 0.25)
			(keepout
				(tracks not_allowed)
				(vias allowed)
				(pads allowed)
				(copperpour not_allowed)
				(footprints allowed)
			)
			(placement
				(enabled no)
				(sheetname "")
			)
			(fill
				(thermal_gap 0.5)
				(thermal_bridge_width 0.5)
				(island_removal_mode 0)
			)
			(polygon
				(pts
					(xy 86.205568 -140.7033) (xy 86.205568 -139.7127) (xy 86.713568 -139.7127) (xy 86.713568 -140.7033)
				)
			)
		)
	)
	(footprint ""
		(layer "F.Cu")
		(at 182.5752 -55.3974 90)
		(property "Reference" "CT61"
			(at -4.6482 1.49987 90)
			(unlocked yes)
			(layer "F.SilkS")
			(effects
				(font
					(size 0.7874 0.5842)
					(thickness 0.1524)
				)
				(justify left)
			)
		)
		(property "Value" ""
			(at 0 0 90)
			(layer "F.Fab")
			(effects
				(font
					(size 1.27 1.27)
				)
			)
		)
		(duplicate_pad_numbers_are_jumpers no)
		(fp_poly
			(pts
				(xy 0.3048 -0.1016) (xy 0.3048 0.9906) (xy -0.3048 0.9906) (xy -0.3048 -0.1016)
			)
			(stroke
				(width 0)
				(type default)
			)
			(fill no)
			(layer "F.CrtYd")
		)
		(fp_line
			(start 0.3048 -0.1016)
			(end -0.3048 -0.1016)
			(stroke
				(width 0.1)
				(type default)
			)
			(layer "F.Fab")
		)
		(fp_line
			(start -0.3048 -0.1016)
			(end -0.3048 0.9906)
			(stroke
				(width 0.1)
				(type default)
			)
			(layer "F.Fab")
		)
		(fp_line
			(start 0.3048 0.9906)
			(end 0.3048 -0.1016)
			(stroke
				(width 0.1)
				(type default)
			)
			(layer "F.Fab")
		)
		(fp_line
			(start -0.3048 0.9906)
			(end 0.3048 0.9906)
			(stroke
				(width 0.1)
				(type default)
			)
			(layer "F.Fab")
		)
		(pad "1" smd rect
			(at 0 0 90)
			(size 0.508 0.508)
			(layers "F.Cu" "F.Mask" "F.Paste")
			(net "A_TSENSE_PVCCIO_CPU1")
		)
		(pad "2" smd rect
			(at 0 0.889 90)
			(size 0.508 0.508)
			(layers "F.Cu" "F.Mask" "F.Paste")
			(net "GND")
		)
		(zone
			(layer "F.Cu")
			(hatch none 0.5)
			(connect_pads
				(clearance 0)
			)
			(min_thickness 0.25)
			(keepout
				(tracks allowed)
				(vias not_allowed)
				(pads allowed)
				(copperpour not_allowed)
				(footprints allowed)
			)
			(placement
				(enabled no)
				(sheetname "")
			)
			(fill
				(thermal_gap 0.5)
				(thermal_bridge_width 0.5)
				(island_removal_mode 0)
			)
			(polygon
				(pts
					(xy 182.8292 -55.1434) (xy 182.8292 -55.6514) (xy 183.2102 -55.6514) (xy 183.2102 -55.1434)
				)
			)
		)
		(zone
			(layer "F.Cu")
			(hatch none 0.5)
			(connect_pads
				(clearance 0)
			)
			(min_thickness 0.25)
			(keepout
				(tracks not_allowed)
				(vias allowed)
				(pads allowed)
				(copperpour not_allowed)
				(footprints allowed)
			)
			(placement
				(enabled no)
				(sheetname "")
			)
			(fill
				(thermal_gap 0.5)
				(thermal_bridge_width 0.5)
				(island_removal_mode 0)
			)
			(polygon
				(pts
					(xy 183.2102 -55.1434) (xy 183.2102 -55.6514) (xy 182.8292 -55.6514) (xy 182.8292 -55.1434)
				)
			)
		)
	)
	(footprint ""
		(layer "F.Cu")
		(at 467.995 -42.164 180)
		(property "Reference" "C9F5"
			(at 0 0 180)
			(layer "F.SilkS")
			(hide yes)
			(effects
				(font
					(size 1.27 1.27)
				)
			)
		)
		(property "Value" ""
			(at 0 0 180)
			(layer "F.Fab")
			(effects
				(font
					(size 1.27 1.27)
				)
			)
		)
		(duplicate_pad_numbers_are_jumpers no)
		(fp_poly
			(pts
				(xy 0.3048 -0.1016) (xy 0.3048 0.9906) (xy -0.3048 0.9906) (xy -0.3048 -0.1016)
			)
			(stroke
				(width 0)
				(type default)
			)
			(fill no)
			(layer "F.CrtYd")
		)
		(fp_line
			(start 0.3048 0.9906)
			(end 0.3048 -0.1016)
			(stroke
				(width 0.1)
				(type default)
			)
			(layer "F.Fab")
		)
		(fp_line
			(start 0.3048 -0.1016)
			(end -0.3048 -0.1016)
			(stroke
				(width 0.1)
				(type default)
			)
			(layer "F.Fab")
		)
		(fp_line
			(start -0.3048 0.9906)
			(end 0.3048 0.9906)
			(stroke
				(width 0.1)
				(type default)
			)
			(layer "F.Fab")
		)
		(fp_line
			(start -0.3048 -0.1016)
			(end -0.3048 0.9906)
			(stroke
				(width 0.1)
				(type default)
			)
			(layer "F.Fab")
		)
		(pad "1" smd rect
			(at 0 0 180)
			(size 0.508 0.508)
			(layers "F.Cu" "F.Mask" "F.Paste")
			(net "P3V3_STBY")
		)
		(pad "2" smd rect
			(at 0 0.889 180)
			(size 0.508 0.508)
			(layers "F.Cu" "F.Mask" "F.Paste")
			(net "GND")
		)
		(zone
			(layer "F.Cu")
			(hatch none 0.5)
			(connect_pads
				(clearance 0)
			)
			(min_thickness 0.25)
			(keepout
				(tracks not_allowed)
				(vias allowed)
				(pads allowed)
				(copperpour not_allowed)
				(footprints allowed)
			)
			(placement
				(enabled no)
				(sheetname "")
			)
			(fill
				(thermal_gap 0.5)
				(thermal_bridge_width 0.5)
				(island_removal_mode 0)
			)
			(polygon
				(pts
					(xy 468.249 -42.799) (xy 467.741 -42.799) (xy 467.741 -42.418) (xy 468.249 -42.418)
				)
			)
		)
		(zone
			(layer "F.Cu")
			(hatch none 0.5)
			(connect_pads
				(clearance 0)
			)
			(min_thickness 0.25)
			(keepout
				(tracks allowed)
				(vias not_allowed)
				(pads allowed)
				(copperpour not_allowed)
				(footprints allowed)
			)
			(placement
				(enabled no)
				(sheetname "")
			)
			(fill
				(thermal_gap 0.5)
				(thermal_bridge_width 0.5)
				(island_removal_mode 0)
			)
			(polygon
				(pts
					(xy 468.249 -42.418) (xy 467.741 -42.418) (xy 467.741 -42.799) (xy 468.249 -42.799)
				)
			)
		)
	)
	(footprint ""
		(layer "F.Cu")
		(at 190.9318 -69.8754 180)
		(property "Reference" "CF4"
			(at 0 0 180)
			(layer "F.SilkS")
			(hide yes)
			(effects
				(font
					(size 1.27 1.27)
				)
			)
		)
		(property "Value" "*"
			(at 1.1811 -2.8194 180)
			(unlocked yes)
			(layer "F.Fab")
			(hide yes)
			(effects
				(font
					(size 1.27 1.016)
					(thickness 0.1524)
				)
			)
		)
		(property "Device Type" "SC22P50V2JN-4GP_SMD-BCG-SC22P5A"
			(at 1.1811 -4.3434 180)
			(unlocked yes)
			(layer "F.Fab")
			(hide yes)
			(effects
				(font
					(size 1.27 1.016)
					(thickness 0.1524)
				)
			)
		)
		(duplicate_pad_numbers_are_jumpers no)
		(fp_rect
			(start -0.4318 0.9525)
			(end 0.4318 -0.9525)
			(stroke
				(width 0)
				(type default)
			)
			(fill no)
			(layer "F.CrtYd")
		)
		(fp_rect
			(start -0.4318 0.9525)
			(end 0.4318 -0.9525)
			(stroke
				(width 0)
				(type default)
			)
			(fill no)
			(layer "F.Fab")
		)
		(pad "1" smd custom
			(at 0 -0.4445 180)
			(size 0.1524 0.1524)
			(layers "F.Cu" "F.Mask" "F.Paste")
			(net "VR_PVCCIN_CPU0_AIREF4")
			(options
				(clearance outline)
				(anchor circle)
			)
			(primitives
				(gr_poly
					(pts
						(arc
							(start 0.3048 -0.2032)
							(mid 0.275042 -0.275042)
							(end 0.2032 -0.3048)
						)
						(arc
							(start -0.2032 -0.3048)
							(mid -0.275042 -0.275042)
							(end -0.3048 -0.2032)
						)
						(arc
							(start -0.3048 0.2032)
							(mid -0.275042 0.275042)
							(end -0.2032 0.3048)
						)
						(arc
							(start 0.2032 0.3048)
							(mid 0.275042 0.275042)
							(end 0.3048 0.2032)
						)
					)
					(width 0)
					(fill yes)
				)
			)
		)
		(pad "2" smd custom
			(at 0 0.4445 180)
			(size 0.1524 0.1524)
			(layers "F.Cu" "F.Mask" "F.Paste")
			(net "ISENSE_PVCCIN_CPU0_PH4_IMON")
			(options
				(clearance outline)
				(anchor circle)
			)
			(primitives
				(gr_poly
					(pts
						(arc
							(start 0.3048 -0.2032)
							(mid 0.275042 -0.275042)
							(end 0.2032 -0.3048)
						)
						(arc
							(start -0.2032 -0.3048)
							(mid -0.275042 -0.275042)
							(end -0.3048 -0.2032)
						)
						(arc
							(start -0.3048 0.2032)
							(mid -0.275042 0.275042)
							(end -0.2032 0.3048)
						)
						(arc
							(start 0.2032 0.3048)
							(mid 0.275042 0.275042)
							(end 0.3048 0.2032)
						)
					)
					(width 0)
					(fill yes)
				)
			)
		)
	)
)
